(kicad_pcb
	(version 20260206)
	(generator "pcbnew")
	(generator_version "10.0")
	(general
		(thickness 1.6)
		(legacy_teardrops no)
	)
	(paper "A4")
	(title_block
		(title "04192023_DAF0TMB3IC0_F0TG_MB_C_brd_V02_OCP.brd")
		(comment 1 "Grand Teton / footprint 3955 of 8354 (U25), pads 2780-2890 of 6102")
	)
	(layers
		(0 "F.Cu" signal "TOP")
		(4 "In1.Cu" signal "GND")
		(6 "In2.Cu" signal "IN1")
		(8 "In3.Cu" signal "GND1")
		(10 "In4.Cu" signal "IN2")
		(12 "In5.Cu" signal "GND2")
		(14 "In6.Cu" signal "IN3")
		(16 "In7.Cu" signal "GND3")
		(18 "In8.Cu" signal "VCC")
		(20 "In9.Cu" signal "VCC1")
		(22 "In10.Cu" signal "GND4")
		(24 "In11.Cu" signal "IN4")
		(26 "In12.Cu" signal "GND5")
		(28 "In13.Cu" signal "IN5")
		(30 "In14.Cu" signal "GND6")
		(32 "In15.Cu" signal "IN6")
		(34 "In16.Cu" signal "GND7")
		(2 "B.Cu" signal "BOTTOM")
		(9 "F.Adhes" user "F.Adhesive")
		(11 "B.Adhes" user "B.Adhesive")
		(13 "F.Paste" user "Package Geometry/Pastemask Top")
		(15 "B.Paste" user "Package Geometry/Pastemask Bottom")
		(5 "F.SilkS" user "Ref Des/Silkscreen Top")
		(7 "B.SilkS" user "Ref Des/Silkscreen Bottom")
		(1 "F.Mask" user "Board Geometry/Soldermask Top")
		(3 "B.Mask" user "Board Geometry/Soldermask Bottom")
		(17 "Dwgs.User" user "User.Drawings")
		(19 "Cmts.User" user "User.Comments")
		(21 "Eco1.User" user "User.Eco1")
		(23 "Eco2.User" user "User.Eco2")
		(25 "Edge.Cuts" user "Board Geometry/Outline")
		(27 "Margin" user)
		(31 "F.CrtYd" user "Package Geometry/Place Bound Top")
		(29 "B.CrtYd" user "Package Geometry/Place Bound Bottom")
		(35 "F.Fab" user "Ref Des/Assembly Top")
		(33 "B.Fab" user "Ref Des/Assembly Bottom")
	)
	(footprint ""
		(layer "F.Cu")
		(at 359.867962 -258.880102 180)
		(property "Reference" "U25"
			(at -45.78477 -62.086744 0)
			(unlocked yes)
			(layer "F.SilkS")
			(effects
				(font
					(size 0.7874 0.5842)
					(thickness 0.1524)
				)
			)
		)
		(property "Value" ""
			(at 0 0 180)
			(layer "F.Fab")
			(effects
				(font
					(size 1.27 1.27)
				)
			)
		)
		(duplicate_pad_numbers_are_jumpers no)
		(pad "C47" smd circle
			(at 8.139938 -35.189922 180)
			(size 0.450088 0.450088)
			(layers "F.Cu" "F.Mask" "F.Paste")
			(net "Net_1874")
		)
		(pad "C48" smd circle
			(at 9.079992 -35.189922 180)
			(size 0.450088 0.450088)
			(layers "F.Cu" "F.Mask" "F.Paste")
			(net "Net_1873")
		)
		(pad "C49" smd circle
			(at 10.020046 -35.189922 180)
			(size 0.450088 0.450088)
			(layers "F.Cu" "F.Mask" "F.Paste")
			(net "GND")
		)
		(pad "C50" smd circle
			(at 10.9601 -35.189922 180)
			(size 0.450088 0.450088)
			(layers "F.Cu" "F.Mask" "F.Paste")
			(net "WAFL_CPU0_TX0_CPU1_RX1_DP")
		)
		(pad "C51" smd circle
			(at 11.8999 -35.189922 180)
			(size 0.450088 0.450088)
			(layers "F.Cu" "F.Mask" "F.Paste")
			(net "WAFL_CPU0_TX0_CPU1_RX1_DN")
		)
		(pad "C52" smd circle
			(at 12.839954 -35.189922 180)
			(size 0.450088 0.450088)
			(layers "F.Cu" "F.Mask" "F.Paste")
			(net "GND")
		)
		(pad "C53" smd circle
			(at 13.780008 -35.189922 180)
			(size 0.450088 0.450088)
			(layers "F.Cu" "F.Mask" "F.Paste")
			(net "Net_1928")
		)
		(pad "C54" smd circle
			(at 14.720062 -35.189922 180)
			(size 0.450088 0.450088)
			(layers "F.Cu" "F.Mask" "F.Paste")
			(net "Net_1929")
		)
		(pad "C55" smd circle
			(at 15.660116 -35.189922 180)
			(size 0.450088 0.450088)
			(layers "F.Cu" "F.Mask" "F.Paste")
			(net "GND")
		)
		(pad "C56" smd circle
			(at 16.599916 -35.189922 180)
			(size 0.450088 0.450088)
			(layers "F.Cu" "F.Mask" "F.Paste")
			(net "GND")
		)
		(pad "C57" smd circle
			(at 17.53997 -35.189922 180)
			(size 0.450088 0.450088)
			(layers "F.Cu" "F.Mask" "F.Paste")
			(net "GND")
		)
		(pad "C58" smd circle
			(at 18.480024 -35.189922 180)
			(size 0.450088 0.450088)
			(layers "F.Cu" "F.Mask" "F.Paste")
			(net "Net_1946")
		)
		(pad "C59" smd circle
			(at 19.420078 -35.189922 180)
			(size 0.450088 0.450088)
			(layers "F.Cu" "F.Mask" "F.Paste")
			(net "Net_1950")
		)
		(pad "C60" smd circle
			(at 20.359878 -35.189922 180)
			(size 0.450088 0.450088)
			(layers "F.Cu" "F.Mask" "F.Paste")
			(net "TP_M_A_CPU0_SA_TEST40")
		)
		(pad "C61" smd circle
			(at 21.299932 -35.189922 180)
			(size 0.450088 0.450088)
			(layers "F.Cu" "F.Mask" "F.Paste")
			(net "GND")
		)
		(pad "C62" smd circle
			(at 22.239986 -35.189922 180)
			(size 0.450088 0.450088)
			(layers "F.Cu" "F.Mask" "F.Paste")
			(net "CPU0_BP1")
		)
		(pad "C63" smd circle
			(at 23.18004 -35.189922 180)
			(size 0.450088 0.450088)
			(layers "F.Cu" "F.Mask" "F.Paste")
			(net "CPU0_BP0")
		)
		(pad "C64" smd circle
			(at 24.120094 -35.189922 180)
			(size 0.450088 0.450088)
			(layers "F.Cu" "F.Mask" "F.Paste")
			(net "GND")
		)
		(pad "C65" smd circle
			(at 25.059894 -35.189922 180)
			(size 0.450088 0.450088)
			(layers "F.Cu" "F.Mask" "F.Paste")
			(net "CPU0_XTRIG_R2_L5")
		)
		(pad "C66" smd circle
			(at 25.999948 -35.189922 180)
			(size 0.450088 0.450088)
			(layers "F.Cu" "F.Mask" "F.Paste")
			(net "CPU0_XTRIG_R2_L4")
		)
		(pad "C67" smd circle
			(at 26.940002 -35.189922 180)
			(size 0.450088 0.450088)
			(layers "F.Cu" "F.Mask" "F.Paste")
			(net "GND")
		)
		(pad "C68" smd circle
			(at 27.880056 -35.189922 180)
			(size 0.450088 0.450088)
			(layers "F.Cu" "F.Mask" "F.Paste")
			(net "CPU0_SP5R2")
		)
		(pad "C69" smd circle
			(at 28.82011 -35.189922 180)
			(size 0.450088 0.450088)
			(layers "F.Cu" "F.Mask" "F.Paste")
			(net "GND")
		)
		(pad "C70" smd circle
			(at 29.75991 -35.189922 180)
			(size 0.450088 0.450088)
			(layers "F.Cu" "F.Mask" "F.Paste")
			(net "CPU0_CORETYPE0")
		)
		(pad "C71" smd circle
			(at 30.699964 -35.189922 180)
			(size 0.450088 0.450088)
			(layers "F.Cu" "F.Mask" "F.Paste")
			(net "GND")
		)
		(pad "C72" smd circle
			(at 31.640018 -35.189922 180)
			(size 0.450088 0.450088)
			(layers "F.Cu" "F.Mask" "F.Paste")
			(net "SMB_CPU0_2_R_SCL")
		)
		(pad "C73" smd circle
			(at 32.580072 -35.189922 180)
			(size 0.450088 0.450088)
			(layers "F.Cu" "F.Mask" "F.Paste")
			(net "GND")
		)
		(pad "C74" smd circle
			(at 33.519872 -35.189922 180)
			(size 0.450088 0.450088)
			(layers "F.Cu" "F.Mask" "F.Paste")
			(net "VSENSE_PVDD18_S5_P0_DP")
		)
		(pad "C75" smd circle
			(at 34.459926 -35.189922 180)
			(size 0.450088 0.450088)
			(layers "F.Cu" "F.Mask" "F.Paste")
			(net "GND")
		)
		(pad "CA1" smd circle
			(at -34.459926 14.13002 180)
			(size 0.450088 0.450088)
			(layers "F.Cu" "F.Mask" "F.Paste")
			(net "GND")
		)
		(pad "CA2" smd circle
			(at -33.519872 14.13002 180)
			(size 0.450088 0.450088)
			(layers "F.Cu" "F.Mask" "F.Paste")
			(net "M_G_CPU0_SB_CB<2>")
		)
		(pad "CA3" smd circle
			(at -32.580072 14.13002 180)
			(size 0.450088 0.450088)
			(layers "F.Cu" "F.Mask" "F.Paste")
			(net "M_G_CPU0_SB_CB<1>")
		)
		(pad "CA4" smd circle
			(at -31.640018 14.13002 180)
			(size 0.450088 0.450088)
			(layers "F.Cu" "F.Mask" "F.Paste")
			(net "PVDD11_S3_P0")
		)
		(pad "CA5" smd circle
			(at -30.699964 14.13002 180)
			(size 0.450088 0.450088)
			(layers "F.Cu" "F.Mask" "F.Paste")
			(net "M_K_CPU0_SB_CB<2>")
		)
		(pad "CA6" smd circle
			(at -29.75991 14.13002 180)
			(size 0.450088 0.450088)
			(layers "F.Cu" "F.Mask" "F.Paste")
			(net "GND")
		)
		(pad "CA7" smd circle
			(at -28.82011 14.13002 180)
			(size 0.450088 0.450088)
			(layers "F.Cu" "F.Mask" "F.Paste")
			(net "M_K_CPU0_SB_CB<1>")
		)
		(pad "CA8" smd circle
			(at -27.880056 14.13002 180)
			(size 0.450088 0.450088)
			(layers "F.Cu" "F.Mask" "F.Paste")
			(net "GND")
		)
		(pad "CA9" smd circle
			(at -26.940002 14.13002 180)
			(size 0.450088 0.450088)
			(layers "F.Cu" "F.Mask" "F.Paste")
			(net "M_L_CPU0_SB_CB<2>")
		)
		(pad "CA10" smd circle
			(at -25.999948 14.13002 180)
			(size 0.450088 0.450088)
			(layers "F.Cu" "F.Mask" "F.Paste")
			(net "M_L_CPU0_SB_CB<1>")
		)
		(pad "CA11" smd circle
			(at -25.059894 14.13002 180)
			(size 0.450088 0.450088)
			(layers "F.Cu" "F.Mask" "F.Paste")
			(net "PVDD11_S3_P0")
		)
		(pad "CA12" smd circle
			(at -24.120094 14.13002 180)
			(size 0.450088 0.450088)
			(layers "F.Cu" "F.Mask" "F.Paste")
			(net "M_H_CPU0_SB_CB<2>")
		)
		(pad "CA13" smd circle
			(at -23.18004 14.13002 180)
			(size 0.450088 0.450088)
			(layers "F.Cu" "F.Mask" "F.Paste")
			(net "GND")
		)
		(pad "CA14" smd circle
			(at -22.239986 14.13002 180)
			(size 0.450088 0.450088)
			(layers "F.Cu" "F.Mask" "F.Paste")
			(net "M_H_CPU0_SB_CB<1>")
		)
		(pad "CA15" smd circle
			(at -21.299932 14.13002 180)
			(size 0.450088 0.450088)
			(layers "F.Cu" "F.Mask" "F.Paste")
			(net "GND")
		)
		(pad "CA16" smd circle
			(at -20.359878 14.13002 180)
			(size 0.450088 0.450088)
			(layers "F.Cu" "F.Mask" "F.Paste")
			(net "M_J_CPU0_SB_CB<2>")
		)
		(pad "CA17" smd circle
			(at -19.420078 14.13002 180)
			(size 0.450088 0.450088)
			(layers "F.Cu" "F.Mask" "F.Paste")
			(net "M_J_CPU0_SB_CB<1>")
		)
		(pad "CA18" smd circle
			(at -18.480024 14.13002 180)
			(size 0.450088 0.450088)
			(layers "F.Cu" "F.Mask" "F.Paste")
			(net "PVDD11_S3_P0")
		)
		(pad "CA19" smd circle
			(at -17.53997 14.13002 180)
			(size 0.450088 0.450088)
			(layers "F.Cu" "F.Mask" "F.Paste")
			(net "M_I_CPU0_SB_CB<2>")
		)
		(pad "CA20" smd circle
			(at -16.599916 14.13002 180)
			(size 0.450088 0.450088)
			(layers "F.Cu" "F.Mask" "F.Paste")
			(net "GND")
		)
		(pad "CA21" smd circle
			(at -15.660116 14.13002 180)
			(size 0.450088 0.450088)
			(layers "F.Cu" "F.Mask" "F.Paste")
			(net "M_I_CPU0_SB_CB<1>")
		)
		(pad "CA22" smd circle
			(at -14.720062 14.13002 180)
			(size 0.450088 0.450088)
			(layers "F.Cu" "F.Mask" "F.Paste")
			(net "GND")
		)
		(pad "CA23" smd circle
			(at -13.780008 14.13002 180)
			(size 0.450088 0.450088)
			(layers "F.Cu" "F.Mask" "F.Paste")
			(net "P5E_CPU0_P2_TX_DN<14>")
		)
		(pad "CA24" smd circle
			(at -12.839954 14.13002 180)
			(size 0.450088 0.450088)
			(layers "F.Cu" "F.Mask" "F.Paste")
			(net "P5E_CPU0_P2_TX_DP<14>")
		)
		(pad "CA25" smd circle
			(at -11.8999 14.13002 180)
			(size 0.450088 0.450088)
			(layers "F.Cu" "F.Mask" "F.Paste")
			(net "GND")
		)
		(pad "CA26" smd circle
			(at -10.9601 14.13002 180)
			(size 0.450088 0.450088)
			(layers "F.Cu" "F.Mask" "F.Paste")
			(net "P5E_CPU0_P2_TX_DN<11>")
		)
		(pad "CA27" smd circle
			(at -10.020046 14.13002 180)
			(size 0.450088 0.450088)
			(layers "F.Cu" "F.Mask" "F.Paste")
			(net "P5E_CPU0_P2_TX_DP<11>")
		)
		(pad "CA28" smd circle
			(at -9.079992 14.13002 180)
			(size 0.450088 0.450088)
			(layers "F.Cu" "F.Mask" "F.Paste")
			(net "GND")
		)
		(pad "CA29" smd circle
			(at -8.139938 14.13002 180)
			(size 0.450088 0.450088)
			(layers "F.Cu" "F.Mask" "F.Paste")
			(net "P5E_CPU0_P2_TX_DN<8>")
		)
		(pad "CA30" smd circle
			(at -7.199884 14.13002 180)
			(size 0.450088 0.450088)
			(layers "F.Cu" "F.Mask" "F.Paste")
			(net "P5E_CPU0_P2_TX_DP<8>")
		)
		(pad "CA31" smd circle
			(at -6.260084 14.13002 180)
			(size 0.450088 0.450088)
			(layers "F.Cu" "F.Mask" "F.Paste")
			(net "GND")
		)
		(pad "CA32" smd circle
			(at -5.32003 14.13002 180)
			(size 0.450088 0.450088)
			(layers "F.Cu" "F.Mask" "F.Paste")
			(net "P5E_CPU0_P2_TX_DN<5>")
		)
		(pad "CA33" smd circle
			(at -4.379976 14.13002 180)
			(size 0.450088 0.450088)
			(layers "F.Cu" "F.Mask" "F.Paste")
			(net "P5E_CPU0_P2_TX_DP<5>")
		)
		(pad "CA34" smd circle
			(at -3.439922 14.13002 180)
			(size 0.450088 0.450088)
			(layers "F.Cu" "F.Mask" "F.Paste")
			(net "GND")
		)
		(pad "CA35" smd circle
			(at -2.500122 14.13002 180)
			(size 0.450088 0.450088)
			(layers "F.Cu" "F.Mask" "F.Paste")
			(net "GND")
		)
		(pad "CA36" smd circle
			(at -1.560068 14.13002 180)
			(size 0.450088 0.450088)
			(layers "F.Cu" "F.Mask" "F.Paste")
			(net "GND")
		)
		(pad "CA40" smd circle
			(at 1.260094 14.13002 180)
			(size 0.450088 0.450088)
			(layers "F.Cu" "F.Mask" "F.Paste")
			(net "GND")
		)
		(pad "CA41" smd circle
			(at 2.199894 14.13002 180)
			(size 0.450088 0.450088)
			(layers "F.Cu" "F.Mask" "F.Paste")
			(net "GND")
		)
		(pad "CA42" smd circle
			(at 3.139948 14.13002 180)
			(size 0.450088 0.450088)
			(layers "F.Cu" "F.Mask" "F.Paste")
			(net "GND")
		)
		(pad "CA43" smd circle
			(at 4.080002 14.13002 180)
			(size 0.450088 0.450088)
			(layers "F.Cu" "F.Mask" "F.Paste")
			(net "P5E_CPU0_P0_RX_DP<10>")
		)
		(pad "CA44" smd circle
			(at 5.020056 14.13002 180)
			(size 0.450088 0.450088)
			(layers "F.Cu" "F.Mask" "F.Paste")
			(net "P5E_CPU0_P0_RX_DN<10>")
		)
		(pad "CA45" smd circle
			(at 5.96011 14.13002 180)
			(size 0.450088 0.450088)
			(layers "F.Cu" "F.Mask" "F.Paste")
			(net "GND")
		)
		(pad "CA46" smd circle
			(at 6.89991 14.13002 180)
			(size 0.450088 0.450088)
			(layers "F.Cu" "F.Mask" "F.Paste")
			(net "P5E_CPU0_P0_RX_DP<7>")
		)
		(pad "CA47" smd circle
			(at 7.839964 14.13002 180)
			(size 0.450088 0.450088)
			(layers "F.Cu" "F.Mask" "F.Paste")
			(net "P5E_CPU0_P0_RX_DN<7>")
		)
		(pad "CA48" smd circle
			(at 8.780018 14.13002 180)
			(size 0.450088 0.450088)
			(layers "F.Cu" "F.Mask" "F.Paste")
			(net "GND")
		)
		(pad "CA49" smd circle
			(at 9.720072 14.13002 180)
			(size 0.450088 0.450088)
			(layers "F.Cu" "F.Mask" "F.Paste")
			(net "P5E_CPU0_P0_RX_DP<4>")
		)
		(pad "CA50" smd circle
			(at 10.659872 14.13002 180)
			(size 0.450088 0.450088)
			(layers "F.Cu" "F.Mask" "F.Paste")
			(net "P5E_CPU0_P0_RX_DN<4>")
		)
		(pad "CA51" smd circle
			(at 11.599926 14.13002 180)
			(size 0.450088 0.450088)
			(layers "F.Cu" "F.Mask" "F.Paste")
			(net "GND")
		)
		(pad "CA52" smd circle
			(at 12.53998 14.13002 180)
			(size 0.450088 0.450088)
			(layers "F.Cu" "F.Mask" "F.Paste")
			(net "P5E_CPU0_P0_RX_DP<1>")
		)
		(pad "CA53" smd circle
			(at 13.480034 14.13002 180)
			(size 0.450088 0.450088)
			(layers "F.Cu" "F.Mask" "F.Paste")
			(net "P5E_CPU0_P0_RX_DN<1>")
		)
		(pad "CA54" smd circle
			(at 14.420088 14.13002 180)
			(size 0.450088 0.450088)
			(layers "F.Cu" "F.Mask" "F.Paste")
			(net "GND")
		)
		(pad "CA55" smd circle
			(at 15.359888 14.13002 180)
			(size 0.450088 0.450088)
			(layers "F.Cu" "F.Mask" "F.Paste")
			(net "M_C_CPU0_SB_CB<1>")
		)
		(pad "CA56" smd circle
			(at 16.299942 14.13002 180)
			(size 0.450088 0.450088)
			(layers "F.Cu" "F.Mask" "F.Paste")
			(net "GND")
		)
		(pad "CA57" smd circle
			(at 17.239996 14.13002 180)
			(size 0.450088 0.450088)
			(layers "F.Cu" "F.Mask" "F.Paste")
			(net "M_C_CPU0_SB_CB<2>")
		)
		(pad "CA58" smd circle
			(at 18.18005 14.13002 180)
			(size 0.450088 0.450088)
			(layers "F.Cu" "F.Mask" "F.Paste")
			(net "PVDDIO_P0")
		)
		(pad "CA59" smd circle
			(at 19.120104 14.13002 180)
			(size 0.450088 0.450088)
			(layers "F.Cu" "F.Mask" "F.Paste")
			(net "M_D_CPU0_SB_CB<1>")
		)
		(pad "CA60" smd circle
			(at 20.059904 14.13002 180)
			(size 0.450088 0.450088)
			(layers "F.Cu" "F.Mask" "F.Paste")
			(net "M_D_CPU0_SB_CB<2>")
		)
		(pad "CA61" smd circle
			(at 20.999958 14.13002 180)
			(size 0.450088 0.450088)
			(layers "F.Cu" "F.Mask" "F.Paste")
			(net "GND")
		)
		(pad "CA62" smd circle
			(at 21.940012 14.13002 180)
			(size 0.450088 0.450088)
			(layers "F.Cu" "F.Mask" "F.Paste")
			(net "M_B_CPU0_SB_CB<1>")
		)
		(pad "CA63" smd circle
			(at 22.880066 14.13002 180)
			(size 0.450088 0.450088)
			(layers "F.Cu" "F.Mask" "F.Paste")
			(net "GND")
		)
		(pad "CA64" smd circle
			(at 23.82012 14.13002 180)
			(size 0.450088 0.450088)
			(layers "F.Cu" "F.Mask" "F.Paste")
			(net "M_B_CPU0_SB_CB<2>")
		)
		(pad "CA65" smd circle
			(at 24.75992 14.13002 180)
			(size 0.450088 0.450088)
			(layers "F.Cu" "F.Mask" "F.Paste")
			(net "PVDDIO_P0")
		)
		(pad "CA66" smd circle
			(at 25.699974 14.13002 180)
			(size 0.450088 0.450088)
			(layers "F.Cu" "F.Mask" "F.Paste")
			(net "M_F_CPU0_SB_CB<1>")
		)
		(pad "CA67" smd circle
			(at 26.640028 14.13002 180)
			(size 0.450088 0.450088)
			(layers "F.Cu" "F.Mask" "F.Paste")
			(net "M_F_CPU0_SB_CB<2>")
		)
		(pad "CA68" smd circle
			(at 27.580082 14.13002 180)
			(size 0.450088 0.450088)
			(layers "F.Cu" "F.Mask" "F.Paste")
			(net "GND")
		)
		(pad "CA69" smd circle
			(at 28.519882 14.13002 180)
			(size 0.450088 0.450088)
			(layers "F.Cu" "F.Mask" "F.Paste")
			(net "M_E_CPU0_SB_CB<1>")
		)
		(pad "CA70" smd circle
			(at 29.459936 14.13002 180)
			(size 0.450088 0.450088)
			(layers "F.Cu" "F.Mask" "F.Paste")
			(net "GND")
		)
		(pad "CA71" smd circle
			(at 30.39999 14.13002 180)
			(size 0.450088 0.450088)
			(layers "F.Cu" "F.Mask" "F.Paste")
			(net "M_E_CPU0_SB_CB<2>")
		)
		(pad "CA72" smd circle
			(at 31.340044 14.13002 180)
			(size 0.450088 0.450088)
			(layers "F.Cu" "F.Mask" "F.Paste")
			(net "PVDDIO_P0")
		)
		(pad "CA73" smd circle
			(at 32.280098 14.13002 180)
			(size 0.450088 0.450088)
			(layers "F.Cu" "F.Mask" "F.Paste")
			(net "M_A_CPU0_SB_CB<1>")
		)
		(pad "CA74" smd circle
			(at 33.219898 14.13002 180)
			(size 0.450088 0.450088)
			(layers "F.Cu" "F.Mask" "F.Paste")
			(net "M_A_CPU0_SB_CB<2>")
		)
		(pad "CA75" smd circle
			(at 34.159952 14.13002 180)
			(size 0.450088 0.450088)
			(layers "F.Cu" "F.Mask" "F.Paste")
			(net "GND")
		)
		(pad "CB2" smd circle
			(at -33.990026 14.940026 180)
			(size 0.450088 0.450088)
			(layers "F.Cu" "F.Mask" "F.Paste")
			(net "M_G_CPU0_SB_DQ<0>")
		)
		(pad "CB3" smd circle
			(at -33.049972 14.940026 180)
			(size 0.450088 0.450088)
			(layers "F.Cu" "F.Mask" "F.Paste")
			(net "GND")
		)
		(pad "CB4" smd circle
			(at -32.109918 14.940026 180)
			(size 0.450088 0.450088)
			(layers "F.Cu" "F.Mask" "F.Paste")
			(net "M_G_CPU0_SB_CB<3>")
		)
		(pad "CB5" smd circle
			(at -31.170118 14.940026 180)
			(size 0.450088 0.450088)
			(layers "F.Cu" "F.Mask" "F.Paste")
			(net "GND")
		)
		(pad "CB6" smd circle
			(at -30.230064 14.940026 180)
			(size 0.450088 0.450088)
			(layers "F.Cu" "F.Mask" "F.Paste")
			(net "M_K_CPU0_SB_DQ<0>")
		)
		(pad "CB7" smd circle
			(at -29.29001 14.940026 180)
			(size 0.450088 0.450088)
			(layers "F.Cu" "F.Mask" "F.Paste")
			(net "M_K_CPU0_SB_CB<3>")
		)
		(pad "CB8" smd circle
			(at -28.349956 14.940026 180)
			(size 0.450088 0.450088)
			(layers "F.Cu" "F.Mask" "F.Paste")
			(net "GND")
		)
		(pad "CB9" smd circle
			(at -27.409902 14.940026 180)
			(size 0.450088 0.450088)
			(layers "F.Cu" "F.Mask" "F.Paste")
			(net "M_L_CPU0_SB_DQ<0>")
		)
		(pad "CB10" smd circle
			(at -26.470102 14.940026 180)
			(size 0.450088 0.450088)
			(layers "F.Cu" "F.Mask" "F.Paste")
			(net "GND")
		)
		(pad "CB11" smd circle
			(at -25.530048 14.940026 180)
			(size 0.450088 0.450088)
			(layers "F.Cu" "F.Mask" "F.Paste")
			(net "M_L_CPU0_SB_CB<3>")
		)
	)
)
